(kicad_pcb
	(version 20260206)
	(generator "pcbnew")
	(generator_version "10.0")
	(general
		(thickness 1.6)
		(legacy_teardrops no)
	)
	(paper "A4")
	(title_block
		(title "Wiwynn_Tioga_Pass_MB.brd")
		(comment 1 "Tioga Pass / footprints 4518-4524 of 4770")
	)
	(layers
		(0 "F.Cu" signal "TOP")
		(4 "In1.Cu" signal "L2GND")
		(6 "In2.Cu" signal "L3")
		(8 "In3.Cu" signal "L4GND")
		(10 "In4.Cu" signal "L5")
		(12 "In5.Cu" signal "L6GND")
		(14 "In6.Cu" signal "L7VCC")
		(16 "In7.Cu" signal "L8VCC")
		(18 "In8.Cu" signal "L9GND")
		(20 "In9.Cu" signal "L10")
		(22 "In10.Cu" signal "L11GND")
		(24 "In11.Cu" signal "L12")
		(26 "In12.Cu" signal "L13GND")
		(2 "B.Cu" signal "BOTTOM")
		(9 "F.Adhes" user "F.Adhesive")
		(11 "B.Adhes" user "B.Adhesive")
		(13 "F.Paste" user "Package Geometry/Pastemask Top")
		(15 "B.Paste" user "Package Geometry/Pastemask Bottom")
		(5 "F.SilkS" user "Ref Des/Silkscreen Top")
		(7 "B.SilkS" user "Ref Des/Silkscreen Bottom")
		(1 "F.Mask" user "Board Geometry/Soldermask Top")
		(3 "B.Mask" user "Board Geometry/Soldermask Bottom")
		(17 "Dwgs.User" user "User.Drawings")
		(19 "Cmts.User" user "User.Comments")
		(21 "Eco1.User" user "User.Eco1")
		(23 "Eco2.User" user "User.Eco2")
		(25 "Edge.Cuts" user "Board Geometry/Outline")
		(27 "Margin" user)
		(31 "F.CrtYd" user "Package Geometry/Place Bound Top")
		(29 "B.CrtYd" user "Package Geometry/Place Bound Bottom")
		(35 "F.Fab" user "Ref Des/Assembly Top")
		(33 "B.Fab" user "Ref Des/Assembly Bottom")
	)
	(footprint ""
		(layer "B.Cu")
		(at 401.066 -104.0765 180)
		(property "Reference" "R6W25"
			(at 0.8382 -0.67818 180)
			(unlocked yes)
			(layer "B.SilkS")
			(effects
				(font
					(size 0.4064 0.254)
					(thickness 0.1524)
				)
				(justify left mirror)
			)
		)
		(property "Value" ""
			(at 0 0 0)
			(layer "B.Fab")
			(effects
				(font
					(size 1.27 1.27)
				)
				(justify mirror)
			)
		)
		(duplicate_pad_numbers_are_jumpers no)
		(fp_poly
			(pts
				(xy 0.2794 -0.1016) (xy -0.2794 -0.1016) (xy -0.2794 0.9906) (xy 0.2794 0.9906)
			)
			(stroke
				(width 0)
				(type default)
			)
			(fill no)
			(layer "B.CrtYd")
		)
		(fp_line
			(start 0.2794 0.9906)
			(end -0.2794 0.9906)
			(stroke
				(width 0.1)
				(type default)
			)
			(layer "B.Fab")
		)
		(fp_line
			(start 0.2794 -0.1016)
			(end 0.2794 0.9906)
			(stroke
				(width 0.1)
				(type default)
			)
			(layer "B.Fab")
		)
		(fp_line
			(start -0.2794 0.9906)
			(end -0.2794 -0.1016)
			(stroke
				(width 0.1)
				(type default)
			)
			(layer "B.Fab")
		)
		(fp_line
			(start -0.2794 -0.1016)
			(end 0.2794 -0.1016)
			(stroke
				(width 0.1)
				(type default)
			)
			(layer "B.Fab")
		)
		(pad "1" smd rect
			(at 0 0)
			(size 0.508 0.508)
			(layers "B.Cu" "B.Mask" "B.Paste")
			(net "P3V3_STBY")
		)
		(pad "2" smd rect
			(at 0 0.889)
			(size 0.508 0.508)
			(layers "B.Cu" "B.Mask" "B.Paste")
			(net "SMB_PMBUS_BMC_STBY_LVC3_SCL_R1")
		)
		(zone
			(layer "B.Cu")
			(hatch none 0.5)
			(connect_pads
				(clearance 0)
			)
			(min_thickness 0.25)
			(keepout
				(tracks not_allowed)
				(vias allowed)
				(pads allowed)
				(copperpour not_allowed)
				(footprints allowed)
			)
			(placement
				(enabled no)
				(sheetname "")
			)
			(fill
				(thermal_gap 0.5)
				(thermal_bridge_width 0.5)
				(island_removal_mode 0)
			)
			(polygon
				(pts
					(xy 400.812 -104.7115) (xy 401.32 -104.7115) (xy 401.32 -104.3305) (xy 400.812 -104.3305)
				)
			)
		)
		(zone
			(layer "B.Cu")
			(hatch none 0.5)
			(connect_pads
				(clearance 0)
			)
			(min_thickness 0.25)
			(keepout
				(tracks allowed)
				(vias not_allowed)
				(pads allowed)
				(copperpour not_allowed)
				(footprints allowed)
			)
			(placement
				(enabled no)
				(sheetname "")
			)
			(fill
				(thermal_gap 0.5)
				(thermal_bridge_width 0.5)
				(island_removal_mode 0)
			)
			(polygon
				(pts
					(xy 400.812 -104.3305) (xy 401.32 -104.3305) (xy 401.32 -104.7115) (xy 400.812 -104.7115)
				)
			)
		)
	)
	(footprint ""
		(layer "B.Cu")
		(at 266.397232 -17.7546 90)
		(property "Reference" "C5T8"
			(at -1.848866 0.752348 90)
			(unlocked yes)
			(layer "B.SilkS")
			(effects
				(font
					(size 1.27 0.9652)
					(thickness 0.1524)
				)
				(justify mirror)
			)
		)
		(property "Value" ""
			(at 0 0 90)
			(layer "B.Fab")
			(effects
				(font
					(size 1.27 1.27)
				)
				(justify mirror)
			)
		)
		(duplicate_pad_numbers_are_jumpers no)
		(fp_rect
			(start 0.500126 1.598422)
			(end -0.500126 -0.201422)
			(stroke
				(width 0)
				(type default)
			)
			(fill no)
			(layer "B.CrtYd")
		)
		(fp_line
			(start 0.500126 -0.201422)
			(end -0.500126 -0.201422)
			(stroke
				(width 0.1)
				(type default)
			)
			(layer "B.Fab")
		)
		(fp_line
			(start -0.500126 -0.201422)
			(end -0.500126 1.598422)
			(stroke
				(width 0.1)
				(type default)
			)
			(layer "B.Fab")
		)
		(fp_line
			(start 0.500126 1.598422)
			(end 0.500126 -0.201422)
			(stroke
				(width 0.1)
				(type default)
			)
			(layer "B.Fab")
		)
		(fp_line
			(start -0.500126 1.598422)
			(end 0.500126 1.598422)
			(stroke
				(width 0.1)
				(type default)
			)
			(layer "B.Fab")
		)
		(pad "1" smd rect
			(at 0 0)
			(size 0.889 0.9906)
			(layers "B.Cu" "B.Mask" "B.Paste")
			(net "PVDDQ_ABC")
		)
		(pad "2" smd rect
			(at 0 1.397)
			(size 0.889 0.9906)
			(layers "B.Cu" "B.Mask" "B.Paste")
			(net "GND")
		)
		(zone
			(layer "B.Cu")
			(hatch none 0.5)
			(connect_pads
				(clearance 0)
			)
			(min_thickness 0.25)
			(keepout
				(tracks allowed)
				(vias not_allowed)
				(pads allowed)
				(copperpour not_allowed)
				(footprints allowed)
			)
			(placement
				(enabled no)
				(sheetname "")
			)
			(fill
				(thermal_gap 0.5)
				(thermal_bridge_width 0.5)
				(island_removal_mode 0)
			)
			(polygon
				(pts
					(xy 267.349732 -18.2499) (xy 266.841732 -18.2499) (xy 266.841732 -17.2593) (xy 267.349732 -17.2593)
				)
			)
		)
		(zone
			(layer "B.Cu")
			(hatch none 0.5)
			(connect_pads
				(clearance 0)
			)
			(min_thickness 0.25)
			(keepout
				(tracks not_allowed)
				(vias allowed)
				(pads allowed)
				(copperpour not_allowed)
				(footprints allowed)
			)
			(placement
				(enabled no)
				(sheetname "")
			)
			(fill
				(thermal_gap 0.5)
				(thermal_bridge_width 0.5)
				(island_removal_mode 0)
			)
			(polygon
				(pts
					(xy 267.349732 -18.2499) (xy 266.841732 -18.2499) (xy 266.841732 -17.2593) (xy 267.349732 -17.2593)
				)
			)
		)
	)
	(footprint ""
		(layer "B.Cu")
		(at 269.559532 -3.3528 90)
		(property "Reference" "C5G57"
			(at -1.14681 0.76708 180)
			(unlocked yes)
			(layer "B.SilkS")
			(effects
				(font
					(size 0.7874 0.5842)
					(thickness 0.1524)
				)
				(justify mirror)
			)
		)
		(property "Value" ""
			(at 0 0 90)
			(layer "B.Fab")
			(effects
				(font
					(size 1.27 1.27)
				)
				(justify mirror)
			)
		)
		(duplicate_pad_numbers_are_jumpers no)
		(fp_rect
			(start -0.4953 -0.2032)
			(end 0.4953 1.6002)
			(stroke
				(width 0)
				(type default)
			)
			(fill no)
			(layer "B.CrtYd")
		)
		(fp_line
			(start 0.4953 -0.2032)
			(end -0.4953 -0.2032)
			(stroke
				(width 0.1)
				(type default)
			)
			(layer "B.Fab")
		)
		(fp_line
			(start -0.4953 -0.2032)
			(end -0.4953 1.6002)
			(stroke
				(width 0.1)
				(type default)
			)
			(layer "B.Fab")
		)
		(fp_line
			(start 0.4953 1.6002)
			(end 0.4953 -0.2032)
			(stroke
				(width 0.1)
				(type default)
			)
			(layer "B.Fab")
		)
		(fp_line
			(start -0.4953 1.6002)
			(end 0.4953 1.6002)
			(stroke
				(width 0.1)
				(type default)
			)
			(layer "B.Fab")
		)
		(pad "1" smd rect
			(at 0 0 270)
			(size 0.762 0.889)
			(layers "B.Cu" "B.Mask" "B.Paste")
			(net "PVDDQ_ABC")
		)
		(pad "2" smd rect
			(at 0 1.397 270)
			(size 0.762 0.889)
			(layers "B.Cu" "B.Mask" "B.Paste")
			(net "GND")
		)
		(zone
			(layer "B.Cu")
			(hatch none 0.5)
			(connect_pads
				(clearance 0)
			)
			(min_thickness 0.25)
			(keepout
				(tracks not_allowed)
				(vias allowed)
				(pads allowed)
				(copperpour not_allowed)
				(footprints allowed)
			)
			(placement
				(enabled no)
				(sheetname "")
			)
			(fill
				(thermal_gap 0.5)
				(thermal_bridge_width 0.5)
				(island_removal_mode 0)
			)
			(polygon
				(pts
					(xy 270.004032 -2.9718) (xy 270.512032 -2.9718) (xy 270.512032 -3.7338) (xy 270.004032 -3.7338)
				)
			)
		)
	)
	(footprint ""
		(layer "B.Cu")
		(at 390.5758 -154.278838 180)
		(property "Reference" "C4W4"
			(at 0.8382 -0.67818 180)
			(unlocked yes)
			(layer "B.SilkS")
			(effects
				(font
					(size 0.4064 0.254)
					(thickness 0.1524)
				)
				(justify left mirror)
			)
		)
		(property "Value" ""
			(at 0 0 0)
			(layer "B.Fab")
			(effects
				(font
					(size 1.27 1.27)
				)
				(justify mirror)
			)
		)
		(duplicate_pad_numbers_are_jumpers no)
		(fp_poly
			(pts
				(xy -0.3048 -0.1016) (xy -0.3048 0.9906) (xy 0.3048 0.9906) (xy 0.3048 -0.1016)
			)
			(stroke
				(width 0)
				(type default)
			)
			(fill no)
			(layer "B.CrtYd")
		)
		(fp_line
			(start 0.3048 0.9906)
			(end -0.3048 0.9906)
			(stroke
				(width 0.1)
				(type default)
			)
			(layer "B.Fab")
		)
		(fp_line
			(start 0.3048 -0.1016)
			(end 0.3048 0.9906)
			(stroke
				(width 0.1)
				(type default)
			)
			(layer "B.Fab")
		)
		(fp_line
			(start -0.3048 0.9906)
			(end -0.3048 -0.1016)
			(stroke
				(width 0.1)
				(type default)
			)
			(layer "B.Fab")
		)
		(fp_line
			(start -0.3048 -0.1016)
			(end 0.3048 -0.1016)
			(stroke
				(width 0.1)
				(type default)
			)
			(layer "B.Fab")
		)
		(pad "1" smd rect
			(at 0 0)
			(size 0.508 0.508)
			(layers "B.Cu" "B.Mask" "B.Paste")
			(net "A_TSENSE_P1V05_PCH_STBY_TMON")
		)
		(pad "2" smd rect
			(at 0 0.889)
			(size 0.508 0.508)
			(layers "B.Cu" "B.Mask" "B.Paste")
			(net "GND")
		)
		(zone
			(layer "B.Cu")
			(hatch none 0.5)
			(connect_pads
				(clearance 0)
			)
			(min_thickness 0.25)
			(keepout
				(tracks not_allowed)
				(vias allowed)
				(pads allowed)
				(copperpour not_allowed)
				(footprints allowed)
			)
			(placement
				(enabled no)
				(sheetname "")
			)
			(fill
				(thermal_gap 0.5)
				(thermal_bridge_width 0.5)
				(island_removal_mode 0)
			)
			(polygon
				(pts
					(xy 390.3218 -154.913838) (xy 390.8298 -154.913838) (xy 390.8298 -154.532838) (xy 390.3218 -154.532838)
				)
			)
		)
		(zone
			(layer "B.Cu")
			(hatch none 0.5)
			(connect_pads
				(clearance 0)
			)
			(min_thickness 0.25)
			(keepout
				(tracks allowed)
				(vias not_allowed)
				(pads allowed)
				(copperpour not_allowed)
				(footprints allowed)
			)
			(placement
				(enabled no)
				(sheetname "")
			)
			(fill
				(thermal_gap 0.5)
				(thermal_bridge_width 0.5)
				(island_removal_mode 0)
			)
			(polygon
				(pts
					(xy 390.3218 -154.532838) (xy 390.8298 -154.532838) (xy 390.8298 -154.913838) (xy 390.3218 -154.913838)
				)
			)
		)
	)
	(footprint ""
		(layer "B.Cu")
		(at 442.722 -14.6812 -90)
		(property "Reference" "R1W35"
			(at 0.8382 -0.67818 270)
			(unlocked yes)
			(layer "B.SilkS")
			(effects
				(font
					(size 0.4064 0.254)
					(thickness 0.1524)
				)
				(justify left mirror)
			)
		)
		(property "Value" ""
			(at 0 0 90)
			(layer "B.Fab")
			(effects
				(font
					(size 1.27 1.27)
				)
				(justify mirror)
			)
		)
		(duplicate_pad_numbers_are_jumpers no)
		(fp_poly
			(pts
				(xy 0.2794 -0.1016) (xy -0.2794 -0.1016) (xy -0.2794 0.9906) (xy 0.2794 0.9906)
			)
			(stroke
				(width 0)
				(type default)
			)
			(fill no)
			(layer "B.CrtYd")
		)
		(fp_line
			(start -0.2794 0.9906)
			(end -0.2794 -0.1016)
			(stroke
				(width 0.1)
				(type default)
			)
			(layer "B.Fab")
		)
		(fp_line
			(start 0.2794 0.9906)
			(end -0.2794 0.9906)
			(stroke
				(width 0.1)
				(type default)
			)
			(layer "B.Fab")
		)
		(fp_line
			(start -0.2794 -0.1016)
			(end 0.2794 -0.1016)
			(stroke
				(width 0.1)
				(type default)
			)
			(layer "B.Fab")
		)
		(fp_line
			(start 0.2794 -0.1016)
			(end 0.2794 0.9906)
			(stroke
				(width 0.1)
				(type default)
			)
			(layer "B.Fab")
		)
		(pad "1" smd rect
			(at 0 0 90)
			(size 0.508 0.508)
			(layers "B.Cu" "B.Mask" "B.Paste")
			(net "PVCCIO_CPU0")
		)
		(pad "2" smd rect
			(at 0 0.889 90)
			(size 0.508 0.508)
			(layers "B.Cu" "B.Mask" "B.Paste")
			(net "P0V7_GTL2014_2")
		)
		(zone
			(layer "B.Cu")
			(hatch none 0.5)
			(connect_pads
				(clearance 0)
			)
			(min_thickness 0.25)
			(keepout
				(tracks not_allowed)
				(vias allowed)
				(pads allowed)
				(copperpour not_allowed)
				(footprints allowed)
			)
			(placement
				(enabled no)
				(sheetname "")
			)
			(fill
				(thermal_gap 0.5)
				(thermal_bridge_width 0.5)
				(island_removal_mode 0)
			)
			(polygon
				(pts
					(xy 442.087 -14.4272) (xy 442.087 -14.9352) (xy 442.468 -14.9352) (xy 442.468 -14.4272)
				)
			)
		)
		(zone
			(layer "B.Cu")
			(hatch none 0.5)
			(connect_pads
				(clearance 0)
			)
			(min_thickness 0.25)
			(keepout
				(tracks allowed)
				(vias not_allowed)
				(pads allowed)
				(copperpour not_allowed)
				(footprints allowed)
			)
			(placement
				(enabled no)
				(sheetname "")
			)
			(fill
				(thermal_gap 0.5)
				(thermal_bridge_width 0.5)
				(island_removal_mode 0)
			)
			(polygon
				(pts
					(xy 442.468 -14.4272) (xy 442.468 -14.9352) (xy 442.087 -14.9352) (xy 442.087 -14.4272)
				)
			)
		)
	)
	(footprint ""
		(layer "B.Cu")
		(at 450.8627 -145.21053 -90)
		(property "Reference" "FB25W5"
			(at 0 0 90)
			(layer "B.SilkS")
			(hide yes)
			(effects
				(font
					(size 1.27 1.27)
				)
				(justify mirror)
			)
		)
		(property "Value" "*"
			(at 0.0127 -7.01675 270)
			(unlocked yes)
			(layer "B.Fab")
			(hide yes)
			(effects
				(font
					(size 0.889 0.889)
					(thickness 0.1524)
				)
				(justify mirror)
			)
		)
		(property "Device Type" "BLM15AG121SN-1GP_DISCRET-G-BLMA"
			(at 0.0127 -8.54075 270)
			(unlocked yes)
			(layer "B.Fab")
			(hide yes)
			(effects
				(font
					(size 0.889 0.889)
					(thickness 0.1524)
				)
				(justify mirror)
			)
		)
		(duplicate_pad_numbers_are_jumpers no)
		(fp_line
			(start 0.508 0.9398)
			(end 0.508 0.8636)
			(stroke
				(width 0.1524)
				(type default)
			)
			(layer "B.SilkS")
		)
		(fp_line
			(start -0.508 -0.9398)
			(end 0.508 -0.9398)
			(stroke
				(width 0.1524)
				(type default)
			)
			(layer "B.SilkS")
		)
		(fp_line
			(start 0.508 -0.9398)
			(end 0.508 0.9398)
			(stroke
				(width 0.1524)
				(type default)
			)
			(layer "B.SilkS")
		)
		(fp_rect
			(start 0.508 0.9398)
			(end -0.508 -0.9398)
			(stroke
				(width 0)
				(type default)
			)
			(fill no)
			(layer "B.CrtYd")
		)
		(fp_rect
			(start 0.508 0.9398)
			(end -0.508 -0.9398)
			(stroke
				(width 0)
				(type default)
			)
			(fill no)
			(layer "B.Fab")
		)
		(pad "1" smd custom
			(at 0 -0.4445 90)
			(size 0.1397 0.1397)
			(layers "B.Cu" "B.Mask" "B.Paste")
			(net "XDP_TMS_R")
			(options
				(clearance outline)
				(anchor circle)
			)
			(primitives
				(gr_poly
					(pts
						(arc
							(start -0.1778 0.2794)
							(mid -0.249642 0.249642)
							(end -0.2794 0.1778)
						)
						(arc
							(start -0.2794 -0.1778)
							(mid -0.249642 -0.249642)
							(end -0.1778 -0.2794)
						)
						(arc
							(start 0.1778 -0.2794)
							(mid 0.249642 -0.249642)
							(end 0.2794 -0.1778)
						)
						(arc
							(start 0.2794 0.1778)
							(mid 0.249642 0.249642)
							(end 0.1778 0.2794)
						)
					)
					(width 0)
					(fill yes)
				)
			)
		)
		(pad "2" smd custom
			(at 0 0.4445 90)
			(size 0.1397 0.1397)
			(layers "B.Cu" "B.Mask" "B.Paste")
			(net "XDP_TMS")
			(options
				(clearance outline)
				(anchor circle)
			)
			(primitives
				(gr_poly
					(pts
						(arc
							(start -0.1778 0.2794)
							(mid -0.249642 0.249642)
							(end -0.2794 0.1778)
						)
						(arc
							(start -0.2794 -0.1778)
							(mid -0.249642 -0.249642)
							(end -0.1778 -0.2794)
						)
						(arc
							(start 0.1778 -0.2794)
							(mid 0.249642 -0.249642)
							(end 0.2794 -0.1778)
						)
						(arc
							(start 0.2794 0.1778)
							(mid 0.249642 0.249642)
							(end 0.1778 0.2794)
						)
					)
					(width 0)
					(fill yes)
				)
			)
		)
	)
	(footprint ""
		(layer "B.Cu")
		(at 63.2968 -91.1352 90)
		(property "Reference" "R8N3"
			(at 0 0 90)
			(layer "B.SilkS")
			(hide yes)
			(effects
				(font
					(size 1.27 1.27)
				)
				(justify mirror)
			)
		)
		(property "Value" ""
			(at 0 0 90)
			(layer "B.Fab")
			(effects
				(font
					(size 1.27 1.27)
				)
				(justify mirror)
			)
		)
		(duplicate_pad_numbers_are_jumpers no)
		(fp_poly
			(pts
				(xy 0.2794 -0.1016) (xy -0.2794 -0.1016) (xy -0.2794 0.9906) (xy 0.2794 0.9906)
			)
			(stroke
				(width 0)
				(type default)
			)
			(fill no)
			(layer "B.CrtYd")
		)
		(fp_line
			(start 0.2794 -0.1016)
			(end 0.2794 0.9906)
			(stroke
				(width 0.1)
				(type default)
			)
			(layer "B.Fab")
		)
		(fp_line
			(start -0.2794 -0.1016)
			(end 0.2794 -0.1016)
			(stroke
				(width 0.1)
				(type default)
			)
			(layer "B.Fab")
		)
		(fp_line
			(start 0.2794 0.9906)
			(end -0.2794 0.9906)
			(stroke
				(width 0.1)
				(type default)
			)
			(layer "B.Fab")
		)
		(fp_line
			(start -0.2794 0.9906)
			(end -0.2794 -0.1016)
			(stroke
				(width 0.1)
				(type default)
			)
			(layer "B.Fab")
		)
		(pad "1" smd rect
			(at 0 0 270)
			(size 0.508 0.508)
			(layers "B.Cu" "B.Mask" "B.Paste")
			(net "P3V3_STBY")
		)
		(pad "2" smd rect
			(at 0 0.889 270)
			(size 0.508 0.508)
			(layers "B.Cu" "B.Mask" "B.Paste")
			(net "FM_CPU1_PKGID2")
		)
		(zone
			(layer "B.Cu")
			(hatch none 0.5)
			(connect_pads
				(clearance 0)
			)
			(min_thickness 0.25)
			(keepout
				(tracks allowed)
				(vias not_allowed)
				(pads allowed)
				(copperpour not_allowed)
				(footprints allowed)
			)
			(placement
				(enabled no)
				(sheetname "")
			)
			(fill
				(thermal_gap 0.5)
				(thermal_bridge_width 0.5)
				(island_removal_mode 0)
			)
			(polygon
				(pts
					(xy 63.5508 -91.3892) (xy 63.5508 -90.8812) (xy 63.9318 -90.8812) (xy 63.9318 -91.3892)
				)
			)
		)
		(zone
			(layer "B.Cu")
			(hatch none 0.5)
			(connect_pads
				(clearance 0)
			)
			(min_thickness 0.25)
			(keepout
				(tracks not_allowed)
				(vias allowed)
				(pads allowed)
				(copperpour not_allowed)
				(footprints allowed)
			)
			(placement
				(enabled no)
				(sheetname "")
			)
			(fill
				(thermal_gap 0.5)
				(thermal_bridge_width 0.5)
				(island_removal_mode 0)
			)
			(polygon
				(pts
					(xy 63.9318 -91.3892) (xy 63.9318 -90.8812) (xy 63.5508 -90.8812) (xy 63.5508 -91.3892)
				)
			)
		)
	)
)
